(kicad_pcb
	(version 20260206)
	(generator "pcbnew")
	(generator_version "10.0")
	(general
		(thickness 1.6)
		(legacy_teardrops no)
	)
	(paper "A4")
	(title_block
		(title "04192023_DAF0TMB3IC0_F0TG_MB_C_brd_V02_OCP.brd")
		(comment 1 "Grand Teton / footprints 3394-3400 of 8354")
	)
	(layers
		(0 "F.Cu" signal "TOP")
		(4 "In1.Cu" signal "GND")
		(6 "In2.Cu" signal "IN1")
		(8 "In3.Cu" signal "GND1")
		(10 "In4.Cu" signal "IN2")
		(12 "In5.Cu" signal "GND2")
		(14 "In6.Cu" signal "IN3")
		(16 "In7.Cu" signal "GND3")
		(18 "In8.Cu" signal "VCC")
		(20 "In9.Cu" signal "VCC1")
		(22 "In10.Cu" signal "GND4")
		(24 "In11.Cu" signal "IN4")
		(26 "In12.Cu" signal "GND5")
		(28 "In13.Cu" signal "IN5")
		(30 "In14.Cu" signal "GND6")
		(32 "In15.Cu" signal "IN6")
		(34 "In16.Cu" signal "GND7")
		(2 "B.Cu" signal "BOTTOM")
		(9 "F.Adhes" user "F.Adhesive")
		(11 "B.Adhes" user "B.Adhesive")
		(13 "F.Paste" user "Package Geometry/Pastemask Top")
		(15 "B.Paste" user "Package Geometry/Pastemask Bottom")
		(5 "F.SilkS" user "Ref Des/Silkscreen Top")
		(7 "B.SilkS" user "Ref Des/Silkscreen Bottom")
		(1 "F.Mask" user "Board Geometry/Soldermask Top")
		(3 "B.Mask" user "Board Geometry/Soldermask Bottom")
		(17 "Dwgs.User" user "User.Drawings")
		(19 "Cmts.User" user "User.Comments")
		(21 "Eco1.User" user "User.Eco1")
		(23 "Eco2.User" user "User.Eco2")
		(25 "Edge.Cuts" user "Board Geometry/Outline")
		(27 "Margin" user)
		(31 "F.CrtYd" user "Package Geometry/Place Bound Top")
		(29 "B.CrtYd" user "Package Geometry/Place Bound Bottom")
		(35 "F.Fab" user "Ref Des/Assembly Top")
		(33 "B.Fab" user "Ref Des/Assembly Bottom")
	)
	(footprint ""
		(layer "F.Cu")
		(at 368.427 -413.639 90)
		(property "Reference" "R4215"
			(at 0 0 90)
			(layer "F.SilkS")
			(hide yes)
			(effects
				(font
					(size 1.27 1.27)
				)
			)
		)
		(property "Value" ""
			(at 0 0 90)
			(layer "F.Fab")
			(effects
				(font
					(size 1.27 1.27)
				)
			)
		)
		(duplicate_pad_numbers_are_jumpers no)
		(fp_line
			(start 0.7874 -0.4064)
			(end 0.7874 0.4064)
			(stroke
				(width 0.1524)
				(type default)
			)
			(layer "F.SilkS")
		)
		(fp_line
			(start -0.7874 -0.4064)
			(end 0.7874 -0.4064)
			(stroke
				(width 0.1524)
				(type default)
			)
			(layer "F.SilkS")
		)
		(fp_line
			(start 0.7874 0.4064)
			(end -0.7874 0.4064)
			(stroke
				(width 0.1524)
				(type default)
			)
			(layer "F.SilkS")
		)
		(fp_line
			(start -0.7874 0.4064)
			(end -0.7874 -0.4064)
			(stroke
				(width 0.1524)
				(type default)
			)
			(layer "F.SilkS")
		)
		(fp_line
			(start -0.12065 -0.305054)
			(end -0.12065 -0.2794)
			(stroke
				(width 0.1)
				(type default)
			)
			(layer "F.Fab")
		)
		(fp_line
			(start -0.67945 -0.305054)
			(end -0.12065 -0.305054)
			(stroke
				(width 0.1)
				(type default)
			)
			(layer "F.Fab")
		)
		(fp_line
			(start 0.67945 -0.3048)
			(end 0.67945 0.3048)
			(stroke
				(width 0.1)
				(type default)
			)
			(layer "F.Fab")
		)
		(fp_line
			(start 0.12065 -0.3048)
			(end 0.67945 -0.3048)
			(stroke
				(width 0.1)
				(type default)
			)
			(layer "F.Fab")
		)
		(fp_line
			(start 0.12065 -0.2794)
			(end 0.12065 -0.3048)
			(stroke
				(width 0.1)
				(type default)
			)
			(layer "F.Fab")
		)
		(fp_line
			(start -0.12065 -0.2794)
			(end 0.12065 -0.2794)
			(stroke
				(width 0.1)
				(type default)
			)
			(layer "F.Fab")
		)
		(fp_line
			(start 0.120396 0.2794)
			(end -0.12065 0.2794)
			(stroke
				(width 0.1)
				(type default)
			)
			(layer "F.Fab")
		)
		(fp_line
			(start -0.12065 0.2794)
			(end -0.12065 0.3048)
			(stroke
				(width 0.1)
				(type default)
			)
			(layer "F.Fab")
		)
		(fp_line
			(start 0.67945 0.3048)
			(end 0.120396 0.3048)
			(stroke
				(width 0.1)
				(type default)
			)
			(layer "F.Fab")
		)
		(fp_line
			(start 0.120396 0.3048)
			(end 0.120396 0.2794)
			(stroke
				(width 0.1)
				(type default)
			)
			(layer "F.Fab")
		)
		(fp_line
			(start -0.12065 0.3048)
			(end -0.67945 0.3048)
			(stroke
				(width 0.1)
				(type default)
			)
			(layer "F.Fab")
		)
		(fp_line
			(start -0.67945 0.3048)
			(end -0.67945 -0.305054)
			(stroke
				(width 0.1)
				(type default)
			)
			(layer "F.Fab")
		)
		(pad "1" smd circle
			(at -0.40005 0 90)
			(size 0 0)
			(layers "F.Cu" "F.Mask" "F.Paste")
			(net "FM_THERMAL_ALERT_N")
		)
		(pad "2" smd circle
			(at 0.40005 0 90)
			(size 0 0)
			(layers "F.Cu" "F.Mask" "F.Paste")
			(net "FM_G751_0_ALERT_N")
		)
	)
	(footprint ""
		(layer "F.Cu")
		(at 90.209878 -144.88541)
		(property "Reference" "R8165"
			(at 0 0 0)
			(layer "F.SilkS")
			(hide yes)
			(effects
				(font
					(size 1.27 1.27)
				)
			)
		)
		(property "Value" ""
			(at 0 0 0)
			(layer "F.Fab")
			(effects
				(font
					(size 1.27 1.27)
				)
			)
		)
		(duplicate_pad_numbers_are_jumpers no)
		(fp_line
			(start -0.7874 -0.4064)
			(end 0.7874 -0.4064)
			(stroke
				(width 0.1524)
				(type default)
			)
			(layer "F.SilkS")
		)
		(fp_line
			(start -0.7874 0.4064)
			(end -0.7874 -0.4064)
			(stroke
				(width 0.1524)
				(type default)
			)
			(layer "F.SilkS")
		)
		(fp_line
			(start 0.7874 -0.4064)
			(end 0.7874 0.4064)
			(stroke
				(width 0.1524)
				(type default)
			)
			(layer "F.SilkS")
		)
		(fp_line
			(start 0.7874 0.4064)
			(end -0.7874 0.4064)
			(stroke
				(width 0.1524)
				(type default)
			)
			(layer "F.SilkS")
		)
		(fp_line
			(start -0.67945 -0.305054)
			(end -0.12065 -0.305054)
			(stroke
				(width 0.1)
				(type default)
			)
			(layer "F.Fab")
		)
		(fp_line
			(start -0.67945 0.3048)
			(end -0.67945 -0.305054)
			(stroke
				(width 0.1)
				(type default)
			)
			(layer "F.Fab")
		)
		(fp_line
			(start -0.12065 -0.305054)
			(end -0.12065 -0.2794)
			(stroke
				(width 0.1)
				(type default)
			)
			(layer "F.Fab")
		)
		(fp_line
			(start -0.12065 -0.2794)
			(end 0.12065 -0.2794)
			(stroke
				(width 0.1)
				(type default)
			)
			(layer "F.Fab")
		)
		(fp_line
			(start -0.12065 0.2794)
			(end -0.12065 0.3048)
			(stroke
				(width 0.1)
				(type default)
			)
			(layer "F.Fab")
		)
		(fp_line
			(start -0.12065 0.3048)
			(end -0.67945 0.3048)
			(stroke
				(width 0.1)
				(type default)
			)
			(layer "F.Fab")
		)
		(fp_line
			(start 0.120396 0.2794)
			(end -0.12065 0.2794)
			(stroke
				(width 0.1)
				(type default)
			)
			(layer "F.Fab")
		)
		(fp_line
			(start 0.120396 0.3048)
			(end 0.120396 0.2794)
			(stroke
				(width 0.1)
				(type default)
			)
			(layer "F.Fab")
		)
		(fp_line
			(start 0.12065 -0.3048)
			(end 0.67945 -0.3048)
			(stroke
				(width 0.1)
				(type default)
			)
			(layer "F.Fab")
		)
		(fp_line
			(start 0.12065 -0.2794)
			(end 0.12065 -0.3048)
			(stroke
				(width 0.1)
				(type default)
			)
			(layer "F.Fab")
		)
		(fp_line
			(start 0.67945 -0.3048)
			(end 0.67945 0.3048)
			(stroke
				(width 0.1)
				(type default)
			)
			(layer "F.Fab")
		)
		(fp_line
			(start 0.67945 0.3048)
			(end 0.120396 0.3048)
			(stroke
				(width 0.1)
				(type default)
			)
			(layer "F.Fab")
		)
		(pad "1" smd circle
			(at -0.40005 0)
			(size 0 0)
			(layers "F.Cu" "F.Mask" "F.Paste")
			(net "P3V3_AUX")
		)
		(pad "2" smd circle
			(at 0.40005 0)
			(size 0 0)
			(layers "F.Cu" "F.Mask" "F.Paste")
			(net "PWRGD_PVDDCR_SOC_P1_R")
		)
	)
	(footprint ""
		(layer "F.Cu")
		(at 359.709974 -413.859218 90)
		(property "Reference" "U204"
			(at 0.003048 -1.732534 90)
			(unlocked yes)
			(layer "F.SilkS")
			(effects
				(font
					(size 0.7874 0.5842)
					(thickness 0.1524)
				)
				(justify left)
			)
		)
		(property "Value" ""
			(at 0 0 90)
			(layer "F.Fab")
			(effects
				(font
					(size 1.27 1.27)
				)
			)
		)
		(duplicate_pad_numbers_are_jumpers no)
		(fp_line
			(start 1.400048 -1.100074)
			(end -1.400048 -1.100074)
			(stroke
				(width 0.1524)
				(type default)
			)
			(layer "F.SilkS")
		)
		(fp_line
			(start 1.400048 -1.100074)
			(end 1.400048 1.100074)
			(stroke
				(width 0.1524)
				(type default)
			)
			(layer "F.SilkS")
		)
		(fp_line
			(start 1.400048 1.100074)
			(end -1.400048 1.100074)
			(stroke
				(width 0.1524)
				(type default)
			)
			(layer "F.SilkS")
		)
		(fp_line
			(start -1.400048 1.100074)
			(end -1.400048 -1.100074)
			(stroke
				(width 0.1524)
				(type default)
			)
			(layer "F.SilkS")
		)
		(fp_poly
			(pts
				(xy -2.606548 -0.141986) (xy -2.606548 -1.157986) (xy -1.590548 -0.649986)
			)
			(stroke
				(width 0)
				(type default)
			)
			(fill yes)
			(layer "F.SilkS")
		)
		(fp_line
			(start 0.674878 -1.100074)
			(end 0.674878 1.100074)
			(stroke
				(width 0.1)
				(type default)
			)
			(layer "F.Fab")
		)
		(fp_line
			(start -0.674878 -1.100074)
			(end 0.674878 -1.100074)
			(stroke
				(width 0.1)
				(type default)
			)
			(layer "F.Fab")
		)
		(fp_line
			(start 0.674878 1.100074)
			(end -0.674878 1.100074)
			(stroke
				(width 0.1)
				(type default)
			)
			(layer "F.Fab")
		)
		(fp_line
			(start -0.674878 1.100074)
			(end -0.674878 -1.100074)
			(stroke
				(width 0.1)
				(type default)
			)
			(layer "F.Fab")
		)
		(fp_poly
			(pts
				(xy -1.590548 -0.649986) (xy -2.606548 -1.157986) (xy -2.606548 -0.141986)
			)
			(stroke
				(width 0)
				(type default)
			)
			(fill yes)
			(layer "F.Fab")
		)
		(pad "1" smd rect
			(at -0.94996 -0.649986)
			(size 0.4318 0.6096)
			(layers "F.Cu" "F.Mask" "F.Paste")
			(net "FM_UART_EN")
		)
		(pad "2" smd rect
			(at -0.94996 0)
			(size 0.4318 0.6096)
			(layers "F.Cu" "F.Mask" "F.Paste")
			(net "UART_BMC_BIC_R_RX")
		)
		(pad "3" smd rect
			(at -0.94996 0.649986)
			(size 0.4318 0.6096)
			(layers "F.Cu" "F.Mask" "F.Paste")
			(net "GND")
		)
		(pad "4" smd rect
			(at 0.94996 0.649986)
			(size 0.4318 0.6096)
			(layers "F.Cu" "F.Mask" "F.Paste")
			(net "UART_BMC_BIC_R_BUF_RX")
		)
		(pad "5" smd rect
			(at 0.94996 -0.649986)
			(size 0.4318 0.6096)
			(layers "F.Cu" "F.Mask" "F.Paste")
			(net "P3V3_AUX")
		)
	)
	(footprint ""
		(layer "F.Cu")
		(at 414.316418 -367.796064 180)
		(property "Reference" "C5009"
			(at 0 0 180)
			(layer "F.SilkS")
			(hide yes)
			(effects
				(font
					(size 1.27 1.27)
				)
			)
		)
		(property "Value" ""
			(at 0 0 180)
			(layer "F.Fab")
			(effects
				(font
					(size 1.27 1.27)
				)
			)
		)
		(duplicate_pad_numbers_are_jumpers no)
		(fp_line
			(start 0.7874 0.4064)
			(end -0.7874 0.4064)
			(stroke
				(width 0.1524)
				(type default)
			)
			(layer "F.SilkS")
		)
		(fp_line
			(start 0.7874 -0.4064)
			(end 0.7874 0.4064)
			(stroke
				(width 0.1524)
				(type default)
			)
			(layer "F.SilkS")
		)
		(fp_line
			(start -0.7874 0.4064)
			(end -0.7874 -0.4064)
			(stroke
				(width 0.1524)
				(type default)
			)
			(layer "F.SilkS")
		)
		(fp_line
			(start -0.7874 -0.4064)
			(end 0.7874 -0.4064)
			(stroke
				(width 0.1524)
				(type default)
			)
			(layer "F.SilkS")
		)
		(fp_line
			(start 0.67945 0.3048)
			(end 0.120396 0.3048)
			(stroke
				(width 0.1)
				(type default)
			)
			(layer "F.Fab")
		)
		(fp_line
			(start 0.67945 -0.3048)
			(end 0.67945 0.3048)
			(stroke
				(width 0.1)
				(type default)
			)
			(layer "F.Fab")
		)
		(fp_line
			(start 0.12065 -0.2794)
			(end 0.12065 -0.3048)
			(stroke
				(width 0.1)
				(type default)
			)
			(layer "F.Fab")
		)
		(fp_line
			(start 0.12065 -0.3048)
			(end 0.67945 -0.3048)
			(stroke
				(width 0.1)
				(type default)
			)
			(layer "F.Fab")
		)
		(fp_line
			(start 0.120396 0.3048)
			(end 0.120396 0.2794)
			(stroke
				(width 0.1)
				(type default)
			)
			(layer "F.Fab")
		)
		(fp_line
			(start 0.120396 0.2794)
			(end -0.12065 0.2794)
			(stroke
				(width 0.1)
				(type default)
			)
			(layer "F.Fab")
		)
		(fp_line
			(start -0.12065 0.3048)
			(end -0.67945 0.3048)
			(stroke
				(width 0.1)
				(type default)
			)
			(layer "F.Fab")
		)
		(fp_line
			(start -0.12065 0.2794)
			(end -0.12065 0.3048)
			(stroke
				(width 0.1)
				(type default)
			)
			(layer "F.Fab")
		)
		(fp_line
			(start -0.12065 -0.2794)
			(end 0.12065 -0.2794)
			(stroke
				(width 0.1)
				(type default)
			)
			(layer "F.Fab")
		)
		(fp_line
			(start -0.12065 -0.305054)
			(end -0.12065 -0.2794)
			(stroke
				(width 0.1)
				(type default)
			)
			(layer "F.Fab")
		)
		(fp_line
			(start -0.67945 0.3048)
			(end -0.67945 -0.305054)
			(stroke
				(width 0.1)
				(type default)
			)
			(layer "F.Fab")
		)
		(fp_line
			(start -0.67945 -0.305054)
			(end -0.12065 -0.305054)
			(stroke
				(width 0.1)
				(type default)
			)
			(layer "F.Fab")
		)
		(pad "1" smd circle
			(at -0.40005 0 180)
			(size 0 0)
			(layers "F.Cu" "F.Mask" "F.Paste")
			(net "PVDD11_S3_P0_PMALERT")
		)
		(pad "2" smd circle
			(at 0.40005 0 180)
			(size 0 0)
			(layers "F.Cu" "F.Mask" "F.Paste")
			(net "GND")
		)
	)
	(footprint ""
		(layer "F.Cu")
		(at 298.527724 -395.333474)
		(property "Reference" "R596"
			(at 0 0 0)
			(layer "F.SilkS")
			(hide yes)
			(effects
				(font
					(size 1.27 1.27)
				)
			)
		)
		(property "Value" ""
			(at 0 0 0)
			(layer "F.Fab")
			(effects
				(font
					(size 1.27 1.27)
				)
			)
		)
		(duplicate_pad_numbers_are_jumpers no)
		(fp_line
			(start -0.32512 -0.175006)
			(end 0.32512 -0.175006)
			(stroke
				(width 0.1)
				(type default)
			)
			(layer "F.Fab")
		)
		(fp_line
			(start -0.32512 0.175006)
			(end -0.32512 -0.175006)
			(stroke
				(width 0.1)
				(type default)
			)
			(layer "F.Fab")
		)
		(fp_line
			(start 0.32512 -0.175006)
			(end 0.32512 0.175006)
			(stroke
				(width 0.1)
				(type default)
			)
			(layer "F.Fab")
		)
		(fp_line
			(start 0.32512 0.175006)
			(end -0.32512 0.175006)
			(stroke
				(width 0.1)
				(type default)
			)
			(layer "F.Fab")
		)
		(pad "1" smd rect
			(at -0.2667 0)
			(size 0.3048 0.381)
			(layers "F.Cu" "F.Mask" "F.Paste")
			(net "CLK_100M_RETIMER_CPU0_P0_R_DN")
		)
		(pad "2" smd rect
			(at 0.2667 0 180)
			(size 0.3048 0.381)
			(layers "F.Cu" "F.Mask" "F.Paste")
			(net "CLK_100M_RETIMER_CPU0_P0_DN")
		)
	)
	(footprint ""
		(layer "F.Cu")
		(at 107.517946 -52.86248 -90)
		(property "Reference" "R6311"
			(at 0 0 270)
			(layer "F.SilkS")
			(hide yes)
			(effects
				(font
					(size 1.27 1.27)
				)
			)
		)
		(property "Value" ""
			(at 0 0 270)
			(layer "F.Fab")
			(effects
				(font
					(size 1.27 1.27)
				)
			)
		)
		(duplicate_pad_numbers_are_jumpers no)
		(fp_line
			(start -0.7874 0.4064)
			(end -0.7874 -0.4064)
			(stroke
				(width 0.1524)
				(type default)
			)
			(layer "F.SilkS")
		)
		(fp_line
			(start 0.7874 0.4064)
			(end -0.7874 0.4064)
			(stroke
				(width 0.1524)
				(type default)
			)
			(layer "F.SilkS")
		)
		(fp_line
			(start -0.7874 -0.4064)
			(end 0.7874 -0.4064)
			(stroke
				(width 0.1524)
				(type default)
			)
			(layer "F.SilkS")
		)
		(fp_line
			(start 0.7874 -0.4064)
			(end 0.7874 0.4064)
			(stroke
				(width 0.1524)
				(type default)
			)
			(layer "F.SilkS")
		)
		(fp_line
			(start -0.67945 0.3048)
			(end -0.67945 -0.305054)
			(stroke
				(width 0.1)
				(type default)
			)
			(layer "F.Fab")
		)
		(fp_line
			(start -0.12065 0.3048)
			(end -0.67945 0.3048)
			(stroke
				(width 0.1)
				(type default)
			)
			(layer "F.Fab")
		)
		(fp_line
			(start 0.120396 0.3048)
			(end 0.120396 0.2794)
			(stroke
				(width 0.1)
				(type default)
			)
			(layer "F.Fab")
		)
		(fp_line
			(start 0.67945 0.3048)
			(end 0.120396 0.3048)
			(stroke
				(width 0.1)
				(type default)
			)
			(layer "F.Fab")
		)
		(fp_line
			(start -0.12065 0.2794)
			(end -0.12065 0.3048)
			(stroke
				(width 0.1)
				(type default)
			)
			(layer "F.Fab")
		)
		(fp_line
			(start 0.120396 0.2794)
			(end -0.12065 0.2794)
			(stroke
				(width 0.1)
				(type default)
			)
			(layer "F.Fab")
		)
		(fp_line
			(start -0.12065 -0.2794)
			(end 0.12065 -0.2794)
			(stroke
				(width 0.1)
				(type default)
			)
			(layer "F.Fab")
		)
		(fp_line
			(start 0.12065 -0.2794)
			(end 0.12065 -0.3048)
			(stroke
				(width 0.1)
				(type default)
			)
			(layer "F.Fab")
		)
		(fp_line
			(start 0.12065 -0.3048)
			(end 0.67945 -0.3048)
			(stroke
				(width 0.1)
				(type default)
			)
			(layer "F.Fab")
		)
		(fp_line
			(start 0.67945 -0.3048)
			(end 0.67945 0.3048)
			(stroke
				(width 0.1)
				(type default)
			)
			(layer "F.Fab")
		)
		(fp_line
			(start -0.67945 -0.305054)
			(end -0.12065 -0.305054)
			(stroke
				(width 0.1)
				(type default)
			)
			(layer "F.Fab")
		)
		(fp_line
			(start -0.12065 -0.305054)
			(end -0.12065 -0.2794)
			(stroke
				(width 0.1)
				(type default)
			)
			(layer "F.Fab")
		)
		(pad "1" smd circle
			(at -0.40005 0 270)
			(size 0 0)
			(layers "F.Cu" "F.Mask" "F.Paste")
			(net "SMB_USB_CPU0_HUB1_SDA")
		)
		(pad "2" smd circle
			(at 0.40005 0 270)
			(size 0 0)
			(layers "F.Cu" "F.Mask" "F.Paste")
			(net "USB_HUB2_TI_OVERCUR1_MRP_PROG_FUNC4")
		)
	)
	(footprint ""
		(layer "F.Cu")
		(at 46.70806 -99.60864 90)
		(property "Reference" "R896"
			(at 0 0 90)
			(layer "F.SilkS")
			(hide yes)
			(effects
				(font
					(size 1.27 1.27)
				)
			)
		)
		(property "Value" ""
			(at 0 0 90)
			(layer "F.Fab")
			(effects
				(font
					(size 1.27 1.27)
				)
			)
		)
		(duplicate_pad_numbers_are_jumpers no)
		(fp_line
			(start 0.7874 -0.4064)
			(end 0.7874 0.4064)
			(stroke
				(width 0.1524)
				(type default)
			)
			(layer "F.SilkS")
		)
		(fp_line
			(start -0.7874 -0.4064)
			(end 0.7874 -0.4064)
			(stroke
				(width 0.1524)
				(type default)
			)
			(layer "F.SilkS")
		)
		(fp_line
			(start 0.7874 0.4064)
			(end -0.7874 0.4064)
			(stroke
				(width 0.1524)
				(type default)
			)
			(layer "F.SilkS")
		)
		(fp_line
			(start -0.7874 0.4064)
			(end -0.7874 -0.4064)
			(stroke
				(width 0.1524)
				(type default)
			)
			(layer "F.SilkS")
		)
		(fp_line
			(start -0.12065 -0.305054)
			(end -0.12065 -0.2794)
			(stroke
				(width 0.1)
				(type default)
			)
			(layer "F.Fab")
		)
		(fp_line
			(start -0.67945 -0.305054)
			(end -0.12065 -0.305054)
			(stroke
				(width 0.1)
				(type default)
			)
			(layer "F.Fab")
		)
		(fp_line
			(start 0.67945 -0.3048)
			(end 0.67945 0.3048)
			(stroke
				(width 0.1)
				(type default)
			)
			(layer "F.Fab")
		)
		(fp_line
			(start 0.12065 -0.3048)
			(end 0.67945 -0.3048)
			(stroke
				(width 0.1)
				(type default)
			)
			(layer "F.Fab")
		)
		(fp_line
			(start 0.12065 -0.2794)
			(end 0.12065 -0.3048)
			(stroke
				(width 0.1)
				(type default)
			)
			(layer "F.Fab")
		)
		(fp_line
			(start -0.12065 -0.2794)
			(end 0.12065 -0.2794)
			(stroke
				(width 0.1)
				(type default)
			)
			(layer "F.Fab")
		)
		(fp_line
			(start 0.120396 0.2794)
			(end -0.12065 0.2794)
			(stroke
				(width 0.1)
				(type default)
			)
			(layer "F.Fab")
		)
		(fp_line
			(start -0.12065 0.2794)
			(end -0.12065 0.3048)
			(stroke
				(width 0.1)
				(type default)
			)
			(layer "F.Fab")
		)
		(fp_line
			(start 0.67945 0.3048)
			(end 0.120396 0.3048)
			(stroke
				(width 0.1)
				(type default)
			)
			(layer "F.Fab")
		)
		(fp_line
			(start 0.120396 0.3048)
			(end 0.120396 0.2794)
			(stroke
				(width 0.1)
				(type default)
			)
			(layer "F.Fab")
		)
		(fp_line
			(start -0.12065 0.3048)
			(end -0.67945 0.3048)
			(stroke
				(width 0.1)
				(type default)
			)
			(layer "F.Fab")
		)
		(fp_line
			(start -0.67945 0.3048)
			(end -0.67945 -0.305054)
			(stroke
				(width 0.1)
				(type default)
			)
			(layer "F.Fab")
		)
		(pad "1" smd circle
			(at -0.40005 0 90)
			(size 0 0)
			(layers "F.Cu" "F.Mask" "F.Paste")
			(net "P12V_AUX")
		)
		(pad "2" smd circle
			(at 0.40005 0 90)
			(size 0 0)
			(layers "F.Cu" "F.Mask" "F.Paste")
			(net "P3V3_AUX_DSC_VOL")
		)
	)
)
